(kicad_pcb
	(version 20260206)
	(generator "pcbnew")
	(generator_version "10.0")
	(general
		(thickness 1.6)
		(legacy_teardrops no)
	)
	(paper "A4")
	(title_block
		(title "pdpb — Lightning_PDPB_BRD.brd")
		(comment 1 "Lightning (Wiwynn / Facebook NVMe JBOF) / footprints 606-612 of 1140")
	)
	(layers
		(0 "F.Cu" signal "TOP")
		(4 "In1.Cu" signal "L2GND")
		(6 "In2.Cu" signal "L3")
		(8 "In3.Cu" signal "L4VCC")
		(10 "In4.Cu" signal "L5VCC")
		(12 "In5.Cu" signal "L6")
		(14 "In6.Cu" signal "L7GND")
		(2 "B.Cu" signal "BOTTOM")
		(9 "F.Adhes" user "F.Adhesive")
		(11 "B.Adhes" user "B.Adhesive")
		(13 "F.Paste" user "Package Geometry/Pastemask Top")
		(15 "B.Paste" user "Package Geometry/Pastemask Bottom")
		(5 "F.SilkS" user "Ref Des/Silkscreen Top")
		(7 "B.SilkS" user "Ref Des/Silkscreen Bottom")
		(1 "F.Mask" user "Board Geometry/Soldermask Top")
		(3 "B.Mask" user "Board Geometry/Soldermask Bottom")
		(17 "Dwgs.User" user "User.Drawings")
		(19 "Cmts.User" user "User.Comments")
		(21 "Eco1.User" user "User.Eco1")
		(23 "Eco2.User" user "User.Eco2")
		(25 "Edge.Cuts" user "Board Geometry/Outline")
		(27 "Margin" user)
		(31 "F.CrtYd" user "Package Geometry/Place Bound Top")
		(29 "B.CrtYd" user "Package Geometry/Place Bound Bottom")
		(35 "F.Fab" user "Ref Des/Assembly Top")
		(33 "B.Fab" user "Ref Des/Assembly Bottom")
	)
	(footprint ""
		(layer "F.Cu")
		(at 51.562 -138.303)
		(property "Reference" "R322"
			(at 0 0 0)
			(layer "F.SilkS")
			(hide yes)
			(effects
				(font
					(size 1.27 1.27)
				)
			)
		)
		(property "Value" "4K7R2J-2-GP"
			(at 0.064008 -3.993896 0)
			(unlocked yes)
			(layer "F.Fab")
			(hide yes)
			(effects
				(font
					(size 1.016 1.016)
					(thickness 0.1524)
				)
			)
		)
		(property "Device Type" "R402H16"
			(at 0.064008 -5.517896 0)
			(unlocked yes)
			(layer "F.Fab")
			(hide yes)
			(effects
				(font
					(size 1.016 1.016)
					(thickness 0.1524)
				)
			)
		)
		(duplicate_pad_numbers_are_jumpers no)
		(fp_line
			(start -0.508 -0.9398)
			(end -0.508 0.9398)
			(stroke
				(width 0.1524)
				(type default)
			)
			(layer "F.SilkS")
		)
		(fp_line
			(start 0.508 -0.9398)
			(end -0.508 -0.9398)
			(stroke
				(width 0.1524)
				(type default)
			)
			(layer "F.SilkS")
		)
		(fp_rect
			(start -0.508 0.9398)
			(end 0.508 -0.9398)
			(stroke
				(width 0)
				(type default)
			)
			(fill no)
			(layer "F.CrtYd")
		)
		(fp_rect
			(start -0.508 0.9398)
			(end 0.508 -0.9398)
			(stroke
				(width 0)
				(type default)
			)
			(fill no)
			(layer "F.Fab")
		)
		(pad "1" smd custom
			(at 0 -0.4445)
			(size 0.1397 0.1397)
			(layers "F.Cu" "F.Mask" "F.Paste")
			(net "P3V3")
			(options
				(clearance outline)
				(anchor circle)
			)
			(primitives
				(gr_poly
					(pts
						(arc
							(start -0.1778 -0.2794)
							(mid -0.249642 -0.249642)
							(end -0.2794 -0.1778)
						)
						(arc
							(start -0.2794 0.1778)
							(mid -0.249642 0.249642)
							(end -0.1778 0.2794)
						)
						(arc
							(start 0.1778 0.2794)
							(mid 0.249642 0.249642)
							(end 0.2794 0.1778)
						)
						(arc
							(start 0.2794 -0.1778)
							(mid 0.249642 -0.249642)
							(end 0.1778 -0.2794)
						)
					)
					(width 0)
					(fill yes)
				)
			)
		)
		(pad "2" smd custom
			(at 0 0.4445)
			(size 0.1397 0.1397)
			(layers "F.Cu" "F.Mask" "F.Paste")
			(net "I2C_B_TMP1_A0")
			(options
				(clearance outline)
				(anchor circle)
			)
			(primitives
				(gr_poly
					(pts
						(arc
							(start -0.1778 -0.2794)
							(mid -0.249642 -0.249642)
							(end -0.2794 -0.1778)
						)
						(arc
							(start -0.2794 0.1778)
							(mid -0.249642 0.249642)
							(end -0.1778 0.2794)
						)
						(arc
							(start 0.1778 0.2794)
							(mid 0.249642 0.249642)
							(end 0.2794 0.1778)
						)
						(arc
							(start 0.2794 -0.1778)
							(mid 0.249642 -0.249642)
							(end 0.1778 -0.2794)
						)
					)
					(width 0)
					(fill yes)
				)
			)
		)
	)
	(footprint ""
		(layer "F.Cu")
		(at 225.1075 -451.4215 90)
		(property "Reference" "R9912"
			(at 0 0 90)
			(layer "F.SilkS")
			(hide yes)
			(effects
				(font
					(size 1.27 1.27)
				)
			)
		)
		(property "Value" "47KR2J-2-GP"
			(at 0.064008 -3.993896 90)
			(unlocked yes)
			(layer "F.Fab")
			(hide yes)
			(effects
				(font
					(size 1.016 1.016)
					(thickness 0.1524)
				)
			)
		)
		(property "Device Type" "R402H16"
			(at 0.064008 -5.517896 90)
			(unlocked yes)
			(layer "F.Fab")
			(hide yes)
			(effects
				(font
					(size 1.016 1.016)
					(thickness 0.1524)
				)
			)
		)
		(duplicate_pad_numbers_are_jumpers no)
		(fp_line
			(start 0.508 -0.9398)
			(end -0.508 -0.9398)
			(stroke
				(width 0.1524)
				(type default)
			)
			(layer "F.SilkS")
		)
		(fp_line
			(start -0.508 -0.9398)
			(end -0.508 0.9398)
			(stroke
				(width 0.1524)
				(type default)
			)
			(layer "F.SilkS")
		)
		(fp_rect
			(start -0.508 0.9398)
			(end 0.508 -0.9398)
			(stroke
				(width 0)
				(type default)
			)
			(fill no)
			(layer "F.CrtYd")
		)
		(fp_rect
			(start -0.508 0.9398)
			(end 0.508 -0.9398)
			(stroke
				(width 0)
				(type default)
			)
			(fill no)
			(layer "F.Fab")
		)
		(pad "1" smd custom
			(at 0 -0.4445 90)
			(size 0.1397 0.1397)
			(layers "F.Cu" "F.Mask" "F.Paste")
			(net "P3V3")
			(options
				(clearance outline)
				(anchor circle)
			)
			(primitives
				(gr_poly
					(pts
						(arc
							(start -0.1778 -0.2794)
							(mid -0.249642 -0.249642)
							(end -0.2794 -0.1778)
						)
						(arc
							(start -0.2794 0.1778)
							(mid -0.249642 0.249642)
							(end -0.1778 0.2794)
						)
						(arc
							(start 0.1778 0.2794)
							(mid 0.249642 0.249642)
							(end 0.2794 0.1778)
						)
						(arc
							(start 0.2794 -0.1778)
							(mid 0.249642 -0.249642)
							(end 0.1778 -0.2794)
						)
					)
					(width 0)
					(fill yes)
				)
			)
		)
		(pad "2" smd custom
			(at 0 0.4445 90)
			(size 0.1397 0.1397)
			(layers "F.Cu" "F.Mask" "F.Paste")
			(net "ATTN_LED_DR0_N")
			(options
				(clearance outline)
				(anchor circle)
			)
			(primitives
				(gr_poly
					(pts
						(arc
							(start -0.1778 -0.2794)
							(mid -0.249642 -0.249642)
							(end -0.2794 -0.1778)
						)
						(arc
							(start -0.2794 0.1778)
							(mid -0.249642 0.249642)
							(end -0.1778 0.2794)
						)
						(arc
							(start 0.1778 0.2794)
							(mid 0.249642 0.249642)
							(end 0.2794 0.1778)
						)
						(arc
							(start 0.2794 -0.1778)
							(mid 0.249642 -0.249642)
							(end 0.1778 -0.2794)
						)
					)
					(width 0)
					(fill yes)
				)
			)
		)
	)
	(footprint ""
		(layer "F.Cu")
		(at 234.061 -245.491 -90)
		(property "Reference" "R9894"
			(at 0 0 270)
			(layer "F.SilkS")
			(hide yes)
			(effects
				(font
					(size 1.27 1.27)
				)
			)
		)
		(property "Value" "1K82R2F-1-GP"
			(at 0.064008 -3.993896 270)
			(unlocked yes)
			(layer "F.Fab")
			(hide yes)
			(effects
				(font
					(size 1.016 1.016)
					(thickness 0.1524)
				)
			)
		)
		(property "Device Type" "R402H16"
			(at 0.064008 -5.517896 270)
			(unlocked yes)
			(layer "F.Fab")
			(hide yes)
			(effects
				(font
					(size 1.016 1.016)
					(thickness 0.1524)
				)
			)
		)
		(duplicate_pad_numbers_are_jumpers no)
		(fp_line
			(start -0.508 -0.9398)
			(end -0.508 0.9398)
			(stroke
				(width 0.1524)
				(type default)
			)
			(layer "F.SilkS")
		)
		(fp_line
			(start 0.508 -0.9398)
			(end -0.508 -0.9398)
			(stroke
				(width 0.1524)
				(type default)
			)
			(layer "F.SilkS")
		)
		(fp_rect
			(start -0.508 0.9398)
			(end 0.508 -0.9398)
			(stroke
				(width 0)
				(type default)
			)
			(fill no)
			(layer "F.CrtYd")
		)
		(fp_rect
			(start -0.508 0.9398)
			(end 0.508 -0.9398)
			(stroke
				(width 0)
				(type default)
			)
			(fill no)
			(layer "F.Fab")
		)
		(pad "1" smd custom
			(at 0 -0.4445 270)
			(size 0.1397 0.1397)
			(layers "F.Cu" "F.Mask" "F.Paste")
			(net "P12V")
			(options
				(clearance outline)
				(anchor circle)
			)
			(primitives
				(gr_poly
					(pts
						(arc
							(start -0.1778 -0.2794)
							(mid -0.249642 -0.249642)
							(end -0.2794 -0.1778)
						)
						(arc
							(start -0.2794 0.1778)
							(mid -0.249642 0.249642)
							(end -0.1778 0.2794)
						)
						(arc
							(start 0.1778 0.2794)
							(mid 0.249642 0.249642)
							(end 0.2794 0.1778)
						)
						(arc
							(start 0.2794 -0.1778)
							(mid 0.249642 -0.249642)
							(end 0.1778 -0.2794)
						)
					)
					(width 0)
					(fill yes)
				)
			)
		)
		(pad "2" smd custom
			(at 0 0.4445 270)
			(size 0.1397 0.1397)
			(layers "F.Cu" "F.Mask" "F.Paste")
			(net "DRV_ACT_2")
			(options
				(clearance outline)
				(anchor circle)
			)
			(primitives
				(gr_poly
					(pts
						(arc
							(start -0.1778 -0.2794)
							(mid -0.249642 -0.249642)
							(end -0.2794 -0.1778)
						)
						(arc
							(start -0.2794 0.1778)
							(mid -0.249642 0.249642)
							(end -0.1778 0.2794)
						)
						(arc
							(start 0.1778 0.2794)
							(mid 0.249642 0.249642)
							(end 0.2794 0.1778)
						)
						(arc
							(start 0.2794 -0.1778)
							(mid 0.249642 -0.249642)
							(end 0.1778 -0.2794)
						)
					)
					(width 0)
					(fill yes)
				)
			)
		)
	)
	(footprint ""
		(layer "F.Cu")
		(at 32.131 -185.801 -90)
		(property "Reference" "R404"
			(at 0 0 270)
			(layer "F.SilkS")
			(hide yes)
			(effects
				(font
					(size 1.27 1.27)
				)
			)
		)
		(property "Value" "0R2J-2-GP"
			(at 0.064008 -3.993896 270)
			(unlocked yes)
			(layer "F.Fab")
			(hide yes)
			(effects
				(font
					(size 1.016 1.016)
					(thickness 0.1524)
				)
			)
		)
		(property "Device Type" "R402H16"
			(at 0.064008 -5.517896 270)
			(unlocked yes)
			(layer "F.Fab")
			(hide yes)
			(effects
				(font
					(size 1.016 1.016)
					(thickness 0.1524)
				)
			)
		)
		(duplicate_pad_numbers_are_jumpers no)
		(fp_line
			(start -0.508 -0.9398)
			(end -0.508 0.9398)
			(stroke
				(width 0.1524)
				(type default)
			)
			(layer "F.SilkS")
		)
		(fp_line
			(start 0.508 -0.9398)
			(end -0.508 -0.9398)
			(stroke
				(width 0.1524)
				(type default)
			)
			(layer "F.SilkS")
		)
		(fp_rect
			(start -0.508 0.9398)
			(end 0.508 -0.9398)
			(stroke
				(width 0)
				(type default)
			)
			(fill no)
			(layer "F.CrtYd")
		)
		(fp_rect
			(start -0.508 0.9398)
			(end 0.508 -0.9398)
			(stroke
				(width 0)
				(type default)
			)
			(fill no)
			(layer "F.Fab")
		)
		(pad "1" smd custom
			(at 0 -0.4445 270)
			(size 0.1397 0.1397)
			(layers "F.Cu" "F.Mask" "F.Paste")
			(net "SDA_DR8_R")
			(options
				(clearance outline)
				(anchor circle)
			)
			(primitives
				(gr_poly
					(pts
						(arc
							(start -0.1778 -0.2794)
							(mid -0.249642 -0.249642)
							(end -0.2794 -0.1778)
						)
						(arc
							(start -0.2794 0.1778)
							(mid -0.249642 0.249642)
							(end -0.1778 0.2794)
						)
						(arc
							(start 0.1778 0.2794)
							(mid 0.249642 0.249642)
							(end 0.2794 0.1778)
						)
						(arc
							(start 0.2794 -0.1778)
							(mid 0.249642 -0.249642)
							(end 0.1778 -0.2794)
						)
					)
					(width 0)
					(fill yes)
				)
			)
		)
		(pad "2" smd custom
			(at 0 0.4445 270)
			(size 0.1397 0.1397)
			(layers "F.Cu" "F.Mask" "F.Paste")
			(net "SDA_DR8")
			(options
				(clearance outline)
				(anchor circle)
			)
			(primitives
				(gr_poly
					(pts
						(arc
							(start -0.1778 -0.2794)
							(mid -0.249642 -0.249642)
							(end -0.2794 -0.1778)
						)
						(arc
							(start -0.2794 0.1778)
							(mid -0.249642 0.249642)
							(end -0.1778 0.2794)
						)
						(arc
							(start 0.1778 0.2794)
							(mid 0.249642 0.249642)
							(end 0.2794 0.1778)
						)
						(arc
							(start 0.2794 -0.1778)
							(mid 0.249642 -0.249642)
							(end 0.1778 -0.2794)
						)
					)
					(width 0)
					(fill yes)
				)
			)
		)
	)
	(footprint ""
		(layer "F.Cu")
		(at 210.49996 -48.999902 -90)
		(property "Reference" "U48"
			(at 0 0 270)
			(layer "F.SilkS")
			(hide yes)
			(effects
				(font
					(size 1.27 1.27)
				)
			)
		)
		(property "Value" "TMP75AIDGKR-GP"
			(at -0.1143 -9.1948 270)
			(unlocked yes)
			(layer "F.Fab")
			(hide yes)
			(effects
				(font
					(size 1.016 1.016)
					(thickness 0.1524)
				)
			)
		)
		(property "Device Type" "MSOP8-1H44"
			(at -0.1143 -10.795 270)
			(unlocked yes)
			(layer "F.Fab")
			(hide yes)
			(effects
				(font
					(size 1.016 1.016)
					(thickness 0.1524)
				)
			)
		)
		(duplicate_pad_numbers_are_jumpers no)
		(fp_line
			(start -1.778 1.0922)
			(end -1.778 3.048)
			(stroke
				(width 0.508)
				(type default)
			)
			(layer "F.SilkS")
		)
		(fp_line
			(start -1.9558 1.016)
			(end 1.0795 1.016)
			(stroke
				(width 0.1524)
				(type default)
			)
			(layer "F.SilkS")
		)
		(fp_line
			(start 1.0795 1.016)
			(end 1.0795 -1.016)
			(stroke
				(width 0.1524)
				(type default)
			)
			(layer "F.SilkS")
		)
		(fp_line
			(start -1.4478 -0.0381)
			(end -1.9558 0.4699)
			(stroke
				(width 0.1524)
				(type default)
			)
			(layer "F.SilkS")
		)
		(fp_line
			(start -1.9558 -0.5461)
			(end -1.4478 -0.0381)
			(stroke
				(width 0.1524)
				(type default)
			)
			(layer "F.SilkS")
		)
		(fp_line
			(start -1.9558 -1.016)
			(end -1.9558 1.016)
			(stroke
				(width 0.1524)
				(type default)
			)
			(layer "F.SilkS")
		)
		(fp_line
			(start 1.0795 -1.016)
			(end -1.9558 -1.016)
			(stroke
				(width 0.1524)
				(type default)
			)
			(layer "F.SilkS")
		)
		(fp_poly
			(pts
				(xy -1.1557 -1.016) (xy -1.1557 1.016) (xy 1.1557 1.016) (xy 1.1557 -1.016)
			)
			(stroke
				(width 0)
				(type default)
			)
			(fill yes)
			(layer "F.SilkS")
		)
		(fp_rect
			(start -1.4986 2.4511)
			(end 1.4986 -2.4511)
			(stroke
				(width 0)
				(type default)
			)
			(fill no)
			(layer "F.CrtYd")
		)
		(fp_poly
			(pts
				(xy -2.032 3.302) (xy -2.032 -3.302) (xy 2.032 -3.302) (xy 2.032 -2.1209) (xy 1.4986 -2.1209) (xy 1.4986 -2.4511)
				(xy -1.4986 -2.4511) (xy -1.4986 2.4511) (xy 1.4986 2.4511) (xy 1.4986 -2.1082) (xy 2.032 -2.1082)
				(xy 2.032 3.302)
			)
			(stroke
				(width 0)
				(type default)
			)
			(fill no)
			(layer "F.CrtYd")
		)
		(fp_rect
			(start -2.032 3.302)
			(end 2.032 -3.302)
			(stroke
				(width 0)
				(type default)
			)
			(fill no)
			(layer "F.Fab")
		)
		(pad "1" smd rect
			(at -0.97536 2.05486 270)
			(size 0.3556 1.524)
			(layers "F.Cu" "F.Mask" "F.Paste")
			(net "TMP3_SDA")
		)
		(pad "2" smd rect
			(at -0.32512 2.05486 270)
			(size 0.3556 1.524)
			(layers "F.Cu" "F.Mask" "F.Paste")
			(net "TMP3_SCL")
		)
		(pad "3" smd rect
			(at 0.32512 2.05486 270)
			(size 0.3556 1.524)
			(layers "F.Cu" "F.Mask" "F.Paste")
			(net "I2C_B_TMP3_ALERT")
		)
		(pad "4" smd rect
			(at 0.97536 2.05486 270)
			(size 0.3556 1.524)
			(layers "F.Cu" "F.Mask" "F.Paste")
			(net "GND")
		)
		(pad "5" smd rect
			(at 0.97536 -2.05486 270)
			(size 0.3556 1.524)
			(layers "F.Cu" "F.Mask" "F.Paste")
			(net "I2C_B_TMP3_A2")
		)
		(pad "6" smd rect
			(at 0.32512 -2.05486 270)
			(size 0.3556 1.524)
			(layers "F.Cu" "F.Mask" "F.Paste")
			(net "I2C_B_TMP3_A1")
		)
		(pad "7" smd rect
			(at -0.32512 -2.05486 270)
			(size 0.3556 1.524)
			(layers "F.Cu" "F.Mask" "F.Paste")
			(net "I2C_B_TMP3_A0")
		)
		(pad "8" smd rect
			(at -0.97536 -2.05486 270)
			(size 0.3556 1.524)
			(layers "F.Cu" "F.Mask" "F.Paste")
			(net "P3V3")
		)
	)
	(footprint ""
		(layer "F.Cu")
		(at 82.931 -306.2732 90)
		(property "Reference" "R9351"
			(at 0 0 90)
			(layer "F.SilkS")
			(hide yes)
			(effects
				(font
					(size 1.27 1.27)
				)
			)
		)
		(property "Value" "2D2R2F-GP"
			(at 0.064008 -3.993896 90)
			(unlocked yes)
			(layer "F.Fab")
			(hide yes)
			(effects
				(font
					(size 1.016 1.016)
					(thickness 0.1524)
				)
			)
		)
		(property "Device Type" "R402H16"
			(at 0.064008 -5.517896 90)
			(unlocked yes)
			(layer "F.Fab")
			(hide yes)
			(effects
				(font
					(size 1.016 1.016)
					(thickness 0.1524)
				)
			)
		)
		(duplicate_pad_numbers_are_jumpers no)
		(fp_line
			(start 0.508 -0.9398)
			(end -0.508 -0.9398)
			(stroke
				(width 0.1524)
				(type default)
			)
			(layer "F.SilkS")
		)
		(fp_line
			(start -0.508 -0.9398)
			(end -0.508 0.9398)
			(stroke
				(width 0.1524)
				(type default)
			)
			(layer "F.SilkS")
		)
		(fp_rect
			(start -0.508 0.9398)
			(end 0.508 -0.9398)
			(stroke
				(width 0)
				(type default)
			)
			(fill no)
			(layer "F.CrtYd")
		)
		(fp_rect
			(start -0.508 0.9398)
			(end 0.508 -0.9398)
			(stroke
				(width 0)
				(type default)
			)
			(fill no)
			(layer "F.Fab")
		)
		(pad "1" smd custom
			(at 0 -0.4445 90)
			(size 0.1397 0.1397)
			(layers "F.Cu" "F.Mask" "F.Paste")
			(net "VDD_DIFF_2")
			(options
				(clearance outline)
				(anchor circle)
			)
			(primitives
				(gr_poly
					(pts
						(arc
							(start -0.1778 -0.2794)
							(mid -0.249642 -0.249642)
							(end -0.2794 -0.1778)
						)
						(arc
							(start -0.2794 0.1778)
							(mid -0.249642 0.249642)
							(end -0.1778 0.2794)
						)
						(arc
							(start 0.1778 0.2794)
							(mid 0.249642 0.249642)
							(end 0.2794 0.1778)
						)
						(arc
							(start 0.2794 -0.1778)
							(mid 0.249642 -0.249642)
							(end 0.1778 -0.2794)
						)
					)
					(width 0)
					(fill yes)
				)
			)
		)
		(pad "2" smd custom
			(at 0 0.4445 90)
			(size 0.1397 0.1397)
			(layers "F.Cu" "F.Mask" "F.Paste")
			(net "VDDR_2")
			(options
				(clearance outline)
				(anchor circle)
			)
			(primitives
				(gr_poly
					(pts
						(arc
							(start -0.1778 -0.2794)
							(mid -0.249642 -0.249642)
							(end -0.2794 -0.1778)
						)
						(arc
							(start -0.2794 0.1778)
							(mid -0.249642 0.249642)
							(end -0.1778 0.2794)
						)
						(arc
							(start 0.1778 0.2794)
							(mid 0.249642 0.249642)
							(end 0.2794 0.1778)
						)
						(arc
							(start 0.2794 -0.1778)
							(mid 0.249642 -0.249642)
							(end 0.1778 -0.2794)
						)
					)
					(width 0)
					(fill yes)
				)
			)
		)
	)
	(footprint ""
		(layer "F.Cu")
		(at 43.016424 -42.877994 -90)
		(property "Reference" "R9945"
			(at 0 0 270)
			(layer "F.SilkS")
			(hide yes)
			(effects
				(font
					(size 1.27 1.27)
				)
			)
		)
		(property "Value" "4K7R2J-2-GP"
			(at 0.064008 -3.993896 270)
			(unlocked yes)
			(layer "F.Fab")
			(hide yes)
			(effects
				(font
					(size 1.016 1.016)
					(thickness 0.1524)
				)
			)
		)
		(property "Device Type" "R402H16"
			(at 0.064008 -5.517896 270)
			(unlocked yes)
			(layer "F.Fab")
			(hide yes)
			(effects
				(font
					(size 1.016 1.016)
					(thickness 0.1524)
				)
			)
		)
		(duplicate_pad_numbers_are_jumpers no)
		(fp_line
			(start -0.508 -0.9398)
			(end -0.508 0.9398)
			(stroke
				(width 0.1524)
				(type default)
			)
			(layer "F.SilkS")
		)
		(fp_line
			(start 0.508 -0.9398)
			(end -0.508 -0.9398)
			(stroke
				(width 0.1524)
				(type default)
			)
			(layer "F.SilkS")
		)
		(fp_rect
			(start -0.508 0.9398)
			(end 0.508 -0.9398)
			(stroke
				(width 0)
				(type default)
			)
			(fill no)
			(layer "F.CrtYd")
		)
		(fp_rect
			(start -0.508 0.9398)
			(end 0.508 -0.9398)
			(stroke
				(width 0)
				(type default)
			)
			(fill no)
			(layer "F.Fab")
		)
		(pad "1" smd custom
			(at 0 -0.4445 270)
			(size 0.1397 0.1397)
			(layers "F.Cu" "F.Mask" "F.Paste")
			(net "P3V3")
			(options
				(clearance outline)
				(anchor circle)
			)
			(primitives
				(gr_poly
					(pts
						(arc
							(start -0.1778 -0.2794)
							(mid -0.249642 -0.249642)
							(end -0.2794 -0.1778)
						)
						(arc
							(start -0.2794 0.1778)
							(mid -0.249642 0.249642)
							(end -0.1778 0.2794)
						)
						(arc
							(start 0.1778 0.2794)
							(mid 0.249642 0.249642)
							(end 0.2794 0.1778)
						)
						(arc
							(start 0.2794 -0.1778)
							(mid 0.249642 -0.249642)
							(end 0.1778 -0.2794)
						)
					)
					(width 0)
					(fill yes)
				)
			)
		)
		(pad "2" smd custom
			(at 0 0.4445 270)
			(size 0.1397 0.1397)
			(layers "F.Cu" "F.Mask" "F.Paste")
			(net "ATTN_LED_DR9_MOS_N")
			(options
				(clearance outline)
				(anchor circle)
			)
			(primitives
				(gr_poly
					(pts
						(arc
							(start -0.1778 -0.2794)
							(mid -0.249642 -0.249642)
							(end -0.2794 -0.1778)
						)
						(arc
							(start -0.2794 0.1778)
							(mid -0.249642 0.249642)
							(end -0.1778 0.2794)
						)
						(arc
							(start 0.1778 0.2794)
							(mid 0.249642 0.249642)
							(end 0.2794 0.1778)
						)
						(arc
							(start 0.2794 -0.1778)
							(mid 0.249642 -0.249642)
							(end 0.1778 -0.2794)
						)
					)
					(width 0)
					(fill yes)
				)
			)
		)
	)
)
